(kicad_pcb
	(version 20260206)
	(generator "pcbnew")
	(generator_version "10.0")
	(general
		(thickness 1.6)
		(legacy_teardrops no)
	)
	(paper "A4")
	(title_block
		(title "v1-tray-backplane — T6M_tray_BP_c_1023_1120.brd")
		(comment 1 "Open CloudServer (Microsoft) / footprints 43-45 of 170")
	)
	(layers
		(0 "F.Cu" signal "TOP")
		(4 "In1.Cu" signal "GND")
		(6 "In2.Cu" signal "IN1")
		(8 "In3.Cu" signal "VCC")
		(10 "In4.Cu" signal "VCC1")
		(12 "In5.Cu" signal "IN2")
		(14 "In6.Cu" signal "GND1")
		(2 "B.Cu" signal "BOTTOM")
		(9 "F.Adhes" user "F.Adhesive")
		(11 "B.Adhes" user "B.Adhesive")
		(13 "F.Paste" user "Package Geometry/Pastemask Top")
		(15 "B.Paste" user "Package Geometry/Pastemask Bottom")
		(5 "F.SilkS" user "Ref Des/Silkscreen Top")
		(7 "B.SilkS" user "Ref Des/Silkscreen Bottom")
		(1 "F.Mask" user "Board Geometry/Soldermask Top")
		(3 "B.Mask" user "Board Geometry/Soldermask Bottom")
		(17 "Dwgs.User" user "User.Drawings")
		(19 "Cmts.User" user "User.Comments")
		(21 "Eco1.User" user "User.Eco1")
		(23 "Eco2.User" user "User.Eco2")
		(25 "Edge.Cuts" user "Board Geometry/Outline")
		(27 "Margin" user)
		(31 "F.CrtYd" user "Package Geometry/Place Bound Top")
		(29 "B.CrtYd" user "Package Geometry/Place Bound Bottom")
		(35 "F.Fab" user "Ref Des/Assembly Top")
		(33 "B.Fab" user "Ref Des/Assembly Bottom")
	)
	(footprint ""
		(layer "F.Cu")
		(at 79.810102 -41.500044 180)
		(property "Reference" "H3"
			(at 3.029204 -4.59994 0)
			(unlocked yes)
			(layer "F.SilkS")
			(effects
				(font
					(size 0.7874 0.5842)
					(thickness 0.1524)
				)
				(justify left)
			)
		)
		(property "Value" ""
			(at 0 0 180)
			(layer "F.Fab")
			(effects
				(font
					(size 1.27 1.27)
				)
			)
		)
		(duplicate_pad_numbers_are_jumpers no)
		(fp_poly
			(pts
				(arc
					(start 3.999992 5.999988)
					(mid 0 9.99998)
					(end -3.999992 5.999988)
				)
				(arc
					(start -3.999992 0)
					(mid 0 -3.999992)
					(end 3.999992 0)
				)
			)
			(stroke
				(width 0)
				(type default)
			)
			(fill no)
			(layer "B.CrtYd")
		)
		(fp_poly
			(pts
				(arc
					(start 3.999992 5.999988)
					(mid 0 9.99998)
					(end -3.999992 5.999988)
				)
				(arc
					(start -3.999992 0)
					(mid 0 -3.999992)
					(end 3.999992 0)
				)
			)
			(stroke
				(width 0)
				(type default)
			)
			(fill no)
			(layer "F.CrtYd")
		)
		(pad "" np_thru_hole circle
			(at 0 0 180)
			(size 3.5052 3.5052)
			(drill 3.5052)
			(layers "*.Cu" "*.Mask")
			(clearance 0.381)
			(thermal_gap 0.381)
		)
		(zone
			(layers "F.Cu" "B.Cu" "In1.Cu" "In2.Cu" "In3.Cu" "In4.Cu" "In5.Cu" "In6.Cu")
			(hatch none 0.5)
			(connect_pads
				(clearance 0)
			)
			(min_thickness 0.25)
			(keepout
				(tracks not_allowed)
				(vias allowed)
				(pads allowed)
				(copperpour not_allowed)
				(footprints allowed)
			)
			(placement
				(enabled no)
				(sheetname "")
			)
			(fill
				(thermal_gap 0.5)
				(thermal_bridge_width 0.5)
				(island_removal_mode 0)
			)
			(polygon
				(pts
					(arc
						(start 77.398372 -44.952666)
						(mid 79.810102 -51.007954)
						(end 82.221832 -44.952666)
					)
					(arc
						(start 82.221832 -44.952666)
						(mid 82.108203 -44.789805)
						(end 82.068162 -44.595288)
					)
					(arc
						(start 82.068162 -41.500044)
						(mid 79.810102 -39.241984)
						(end 77.552042 -41.500044)
					)
					(arc
						(start 77.552042 -44.595288)
						(mid 77.512056 -44.789828)
						(end 77.398372 -44.952666)
					)
				)
			)
		)
	)
	(footprint ""
		(layer "F.Cu")
		(at 105.9688 -2.9464 90)
		(property "Reference" "C20"
			(at -2.3876 -4.943348 90)
			(unlocked yes)
			(layer "F.SilkS")
			(effects
				(font
					(size 0.7874 0.5842)
					(thickness 0.1524)
				)
				(justify left)
			)
		)
		(property "Value" ""
			(at 0 0 90)
			(layer "F.Fab")
			(effects
				(font
					(size 1.27 1.27)
				)
			)
		)
		(duplicate_pad_numbers_are_jumpers no)
		(fp_line
			(start 0.7874 -0.4064)
			(end 0.7874 0.4064)
			(stroke
				(width 0.1524)
				(type default)
			)
			(layer "F.SilkS")
		)
		(fp_line
			(start -0.7874 -0.4064)
			(end 0.7874 -0.4064)
			(stroke
				(width 0.1524)
				(type default)
			)
			(layer "F.SilkS")
		)
		(fp_line
			(start 0 0.381)
			(end 0 -0.381)
			(stroke
				(width 0.1524)
				(type default)
			)
			(layer "F.SilkS")
		)
		(fp_line
			(start 0.7874 0.4064)
			(end -0.7874 0.4064)
			(stroke
				(width 0.1524)
				(type default)
			)
			(layer "F.SilkS")
		)
		(fp_line
			(start -0.7874 0.4064)
			(end -0.7874 -0.4064)
			(stroke
				(width 0.1524)
				(type default)
			)
			(layer "F.SilkS")
		)
		(fp_poly
			(pts
				(xy -0.5334 0.254) (xy -0.635 0.254) (xy -0.635 0.2286) (xy -0.635 -0.254) (xy -0.5334 -0.254) (xy -0.5334 -0.2794)
				(xy 0.5334 -0.2794) (xy 0.5334 -0.254) (xy 0.635 -0.254) (xy 0.635 0.254) (xy 0.5334 0.254) (xy 0.5334 0.2794)
				(xy -0.508 0.2794) (xy -0.5334 0.2794)
			)
			(stroke
				(width 0)
				(type default)
			)
			(fill no)
			(layer "F.CrtYd")
		)
		(pad "1" smd rect
			(at 0.40005 0 90)
			(size 0.4572 0.508)
			(layers "F.Cu" "F.Mask" "F.Paste")
			(net "P3V3_10G_2_VCCT")
		)
		(pad "2" smd rect
			(at -0.40005 0 90)
			(size 0.4572 0.508)
			(layers "F.Cu" "F.Mask" "F.Paste")
			(net "GND")
		)
	)
	(footprint ""
		(layer "F.Cu")
		(at 351.177352 -21.092668)
		(property "Reference" "R75"
			(at -58.908696 -4.409948 0)
			(unlocked yes)
			(layer "F.SilkS")
			(effects
				(font
					(size 0.7874 0.5842)
					(thickness 0.1524)
				)
				(justify left)
			)
		)
		(property "Value" ""
			(at 0 0 0)
			(layer "F.Fab")
			(effects
				(font
					(size 1.27 1.27)
				)
			)
		)
		(duplicate_pad_numbers_are_jumpers no)
		(fp_line
			(start -0.7874 -0.4064)
			(end 0.7874 -0.4064)
			(stroke
				(width 0.1524)
				(type default)
			)
			(layer "F.SilkS")
		)
		(fp_line
			(start -0.7874 0.4064)
			(end -0.7874 -0.4064)
			(stroke
				(width 0.1524)
				(type default)
			)
			(layer "F.SilkS")
		)
		(fp_line
			(start 0.7874 -0.4064)
			(end 0.7874 0.4064)
			(stroke
				(width 0.1524)
				(type default)
			)
			(layer "F.SilkS")
		)
		(fp_line
			(start 0.7874 0.4064)
			(end -0.7874 0.4064)
			(stroke
				(width 0.1524)
				(type default)
			)
			(layer "F.SilkS")
		)
		(fp_poly
			(pts
				(xy -0.508 0.2794) (xy -0.508 0.2286) (xy -0.635 0.2286) (xy -0.635 -0.254) (xy -0.5334 -0.254)
				(xy -0.5334 -0.2794) (xy 0.5334 -0.2794) (xy 0.5334 -0.254) (xy 0.635 -0.254) (xy 0.635 0.254) (xy 0.5334 0.254)
				(xy 0.5334 0.2794)
			)
			(stroke
				(width 0)
				(type default)
			)
			(fill no)
			(layer "F.CrtYd")
		)
		(pad "1" smd rect
			(at 0.40005 0)
			(size 0.4572 0.508)
			(layers "F.Cu" "F.Mask" "F.Paste")
			(net "ENET10G_3_MOD_DEF0")
		)
		(pad "2" smd rect
			(at -0.40005 0)
			(size 0.4572 0.508)
			(layers "F.Cu" "F.Mask" "F.Paste")
			(net "SFP3_PRESENT_N")
		)
	)
)
